(kicad_pcb
	(version 20241229)
	(generator "pcbnew")
	(generator_version "9.0")
	(general
		(thickness 1.62)
		(legacy_teardrops no)
	)
	(paper "A4")
	(title_block
		(title "OCuLink to 10GbE adapter")
		(date "2026-02-23")
		(rev "1.1.0")
		(company "Antmicro Ltd")
		(comment 1 "www.antmicro.com")
		(comment 9 "footprints 403-407 of 510")
	)
	(layers
		(0 "F.Cu" signal)
		(4 "In1.Cu" signal)
		(6 "In2.Cu" signal)
		(8 "In3.Cu" signal)
		(10 "In4.Cu" signal)
		(12 "In5.Cu" signal)
		(14 "In6.Cu" signal)
		(2 "B.Cu" signal)
		(9 "F.Adhes" user "F.Adhesive")
		(11 "B.Adhes" user "B.Adhesive")
		(13 "F.Paste" user)
		(15 "B.Paste" user)
		(5 "F.SilkS" user "F.Silkscreen")
		(7 "B.SilkS" user "B.Silkscreen")
		(1 "F.Mask" user)
		(3 "B.Mask" user)
		(17 "Dwgs.User" user "User.Drawings")
		(19 "Cmts.User" user "User.Comments")
		(21 "Eco1.User" user "User.Eco1")
		(23 "Eco2.User" user "User.Eco2")
		(25 "Edge.Cuts" user)
		(27 "Margin" user)
		(31 "F.CrtYd" user "F.Courtyard")
		(29 "B.CrtYd" user "B.Courtyard")
		(35 "F.Fab" user)
		(33 "B.Fab" user)
	)
	(footprint "antmicro-footprints:C_0402_1005Metric"
		(layer "B.Cu")
		(at 87.225 100.15 90)
		(descr "Capacitor SMD 0402")
		(tags "capacitor SMD 0402")
		(property "Reference" "C111"
			(at 9.81 -0.435 90)
			(layer "B.SilkS")
			(effects
				(font
					(size 0.7 0.7)
					(thickness 0.15)
				)
				(justify right top mirror)
			)
		)
		(property "Value" "C_1u_25V_0402"
			(at -1.022927 -2.155213 90)
			(layer "B.Fab")
			(hide yes)
			(effects
				(font
					(size 0.7 0.7)
					(thickness 0.15)
				)
				(justify right top mirror)
			)
		)
		(property "Datasheet" "https://www.murata.com/products/productdetail?partno=GRM155R61E105KE11%23"
			(at 0 0 90)
			(layer "B.Fab")
			(hide yes)
			(effects
				(font
					(size 1.27 1.27)
					(thickness 0.15)
				)
				(justify mirror)
			)
		)
		(property "Description" "SMD Multilayer Ceramic Capacitor, 1 µF, 25 V, 0402 [1005 Metric], ± 10%, X5R, GRM Series"
			(at 0 0 90)
			(layer "B.Fab")
			(hide yes)
			(effects
				(font
					(size 1.27 1.27)
					(thickness 0.15)
				)
				(justify mirror)
			)
		)
		(property "MPN" "GRM155R61E105KE11J"
			(at 0 0 90)
			(unlocked yes)
			(layer "B.Fab")
			(hide yes)
			(effects
				(font
					(size 1 1)
					(thickness 0.15)
				)
				(justify mirror)
			)
		)
		(property "Manufacturer" "Murata"
			(at 0 0 90)
			(unlocked yes)
			(layer "B.Fab")
			(hide yes)
			(effects
				(font
					(size 1 1)
					(thickness 0.15)
				)
				(justify mirror)
			)
		)
		(property "License" "Apache-2.0"
			(at 0 0 90)
			(unlocked yes)
			(layer "B.Fab")
			(hide yes)
			(effects
				(font
					(size 1 1)
					(thickness 0.15)
				)
				(justify mirror)
			)
		)
		(property "Author" "Antmicro"
			(at 0 0 90)
			(unlocked yes)
			(layer "B.Fab")
			(hide yes)
			(effects
				(font
					(size 1 1)
					(thickness 0.15)
				)
				(justify mirror)
			)
		)
		(property "Val" "1u"
			(at 0 0 90)
			(unlocked yes)
			(layer "B.Fab")
			(hide yes)
			(effects
				(font
					(size 1 1)
					(thickness 0.15)
				)
				(justify mirror)
			)
		)
		(property "Voltage" "25V"
			(at 0 0 90)
			(unlocked yes)
			(layer "B.Fab")
			(hide yes)
			(effects
				(font
					(size 1 1)
					(thickness 0.15)
				)
				(justify mirror)
			)
		)
		(property "Dielectric" "X5R"
			(at 0 0 90)
			(unlocked yes)
			(layer "B.Fab")
			(hide yes)
			(effects
				(font
					(size 1 1)
					(thickness 0.15)
				)
				(justify mirror)
			)
		)
		(sheetname "/X710-AT2 power/")
		(sheetfile "x710-at2-power.kicad_sch")
		(attr smd)
		(fp_rect
			(start -0.925 0.47)
			(end 0.925 -0.47)
			(stroke
				(width 0.05)
				(type default)
			)
			(fill no)
			(layer "B.CrtYd")
		)
		(fp_line
			(start 0.504 -0.248)
			(end -0.494 -0.248)
			(stroke
				(width 0.15)
				(type solid)
			)
			(layer "B.Fab")
		)
		(fp_line
			(start -0.494 -0.248)
			(end -0.494 0.25)
			(stroke
				(width 0.15)
				(type solid)
			)
			(layer "B.Fab")
		)
		(fp_line
			(start 0.504 0.25)
			(end 0.504 -0.248)
			(stroke
				(width 0.15)
				(type solid)
			)
			(layer "B.Fab")
		)
		(fp_line
			(start -0.494 0.25)
			(end 0.504 0.25)
			(stroke
				(width 0.15)
				(type solid)
			)
			(layer "B.Fab")
		)
		(pad "1" smd roundrect
			(at -0.48 0 90)
			(size 0.59 0.64)
			(layers "B.Cu" "B.Mask" "B.Paste")
			(roundrect_rratio 0.25)
			(net 28 "GND")
			(pintype "passive")
		)
		(pad "2" smd roundrect
			(at 0.48 0 90)
			(size 0.59 0.64)
			(layers "B.Cu" "B.Mask" "B.Paste")
			(roundrect_rratio 0.25)
			(net 9 "VCCD")
			(pintype "passive")
		)
	)
	(footprint "antmicro-footprints:USON-10_2.5x1mm_P0.5mm"
		(layer "B.Cu")
		(at 102.747999 55.88366 90)
		(descr "USON-10 2.5x1mm_ Pitch 0.5mm")
		(tags "USON-10 2.5x1mm Pitch 0.5mm")
		(property "Reference" "D4"
			(at -0.90134 -0.747999 0)
			(layer "B.SilkS")
			(effects
				(font
					(size 0.7 0.7)
					(thickness 0.15)
				)
				(justify right top mirror)
			)
		)
		(property "Value" "ESD204DQAR"
			(at 0.018 -2.499 90)
			(layer "B.Fab")
			(hide yes)
			(effects
				(font
					(size 0.7 0.7)
					(thickness 0.15)
				)
				(justify right top mirror)
			)
		)
		(property "Datasheet" "https://www.ti.com/lit/ds/symlink/esd204.pdf?ts=1706004844383&ref_url=https%253A%252F%252Fwww.ti.com%252Finterface%252Fdiodes%252Fesd-protection-diodes%252Fproducts.html"
			(at 0 0 90)
			(layer "B.Fab")
			(hide yes)
			(effects
				(font
					(size 1.27 1.27)
					(thickness 0.15)
				)
				(justify mirror)
			)
		)
		(property "Description" "TVS diode array, 30 kV, USON-10, 3.6 V, 0.55 pF"
			(at 0 0 90)
			(layer "B.Fab")
			(hide yes)
			(effects
				(font
					(size 1.27 1.27)
					(thickness 0.15)
				)
				(justify mirror)
			)
		)
		(property "MPN" "ESD204DQAR"
			(at 0 0 90)
			(unlocked yes)
			(layer "B.Fab")
			(hide yes)
			(effects
				(font
					(size 1 1)
					(thickness 0.15)
				)
				(justify mirror)
			)
		)
		(property "Manufacturer" "Texas Instruments"
			(at 0 0 90)
			(unlocked yes)
			(layer "B.Fab")
			(hide yes)
			(effects
				(font
					(size 1 1)
					(thickness 0.15)
				)
				(justify mirror)
			)
		)
		(property "Author" "Antmicro"
			(at 0 0 90)
			(unlocked yes)
			(layer "B.Fab")
			(hide yes)
			(effects
				(font
					(size 1 1)
					(thickness 0.15)
				)
				(justify mirror)
			)
		)
		(property "License" "Apache-2.0"
			(at 0 0 90)
			(unlocked yes)
			(layer "B.Fab")
			(hide yes)
			(effects
				(font
					(size 1 1)
					(thickness 0.15)
				)
				(justify mirror)
			)
		)
		(sheetname "/OCuLink/")
		(sheetfile "oculink.kicad_sch")
		(attr smd)
		(fp_line
			(start 0.498 -1.398)
			(end -0.5 -1.398)
			(stroke
				(width 0.15)
				(type solid)
			)
			(layer "B.SilkS")
		)
		(fp_line
			(start 0.498 1.401)
			(end -0.5 1.401)
			(stroke
				(width 0.15)
				(type solid)
			)
			(layer "B.SilkS")
		)
		(fp_circle
			(center -0.68 1.27)
			(end -0.63 1.27)
			(stroke
				(width 0.15)
				(type solid)
			)
			(fill yes)
			(layer "B.SilkS")
		)
		(fp_rect
			(start -0.8 1.5)
			(end 0.8 -1.499)
			(stroke
				(width 0.05)
				(type solid)
			)
			(fill no)
			(layer "B.CrtYd")
		)
		(fp_line
			(start -0.5 -1.249)
			(end 0.498 -1.249)
			(stroke
				(width 0.15)
				(type solid)
			)
			(layer "B.Fab")
		)
		(fp_line
			(start -0.5 1)
			(end -0.5 -1.249)
			(stroke
				(width 0.15)
				(type solid)
			)
			(layer "B.Fab")
		)
		(fp_line
			(start 0.498 1.25)
			(end 0.498 -1.249)
			(stroke
				(width 0.15)
				(type solid)
			)
			(layer "B.Fab")
		)
		(fp_line
			(start 0.498 1.25)
			(end -0.25 1.25)
			(stroke
				(width 0.15)
				(type solid)
			)
			(layer "B.Fab")
		)
		(fp_line
			(start -0.25 1.25)
			(end -0.5 1)
			(stroke
				(width 0.15)
				(type solid)
			)
			(layer "B.Fab")
		)
		(pad "1" smd roundrect
			(at -0.387 1 180)
			(size 0.25 0.55)
			(layers "B.Cu" "B.Mask" "B.Paste")
			(roundrect_rratio 0.25)
			(net 39 "/OCuLink/PCIe_{x4}.RX0+")
			(pintype "passive")
		)
		(pad "2" smd roundrect
			(at -0.387 0.5 180)
			(size 0.25 0.55)
			(layers "B.Cu" "B.Mask" "B.Paste")
			(roundrect_rratio 0.25)
			(net 36 "/OCuLink/PCIe_{x4}.RX0-")
			(pintype "passive")
		)
		(pad "3" smd roundrect
			(at -0.387 0 180)
			(size 0.4 0.55)
			(layers "B.Cu" "B.Mask" "B.Paste")
			(roundrect_rratio 0.25)
			(net 28 "GND")
			(pintype "power_in")
		)
		(pad "4" smd roundrect
			(at -0.387 -0.498 180)
			(size 0.25 0.55)
			(layers "B.Cu" "B.Mask" "B.Paste")
			(roundrect_rratio 0.25)
			(net 37 "/OCuLink/PCIe_{x4}.RX1+")
			(pintype "passive")
		)
		(pad "5" smd roundrect
			(at -0.387 -0.998 180)
			(size 0.25 0.55)
			(layers "B.Cu" "B.Mask" "B.Paste")
			(roundrect_rratio 0.25)
			(net 34 "/OCuLink/PCIe_{x4}.RX1-")
			(pintype "passive")
		)
		(pad "6" smd roundrect
			(at 0.385 -0.998 180)
			(size 0.25 0.55)
			(layers "B.Cu" "B.Mask" "B.Paste")
			(roundrect_rratio 0.25)
			(net 34 "/OCuLink/PCIe_{x4}.RX1-")
			(pintype "passive")
		)
		(pad "7" smd roundrect
			(at 0.385 -0.498 180)
			(size 0.25 0.55)
			(layers "B.Cu" "B.Mask" "B.Paste")
			(roundrect_rratio 0.25)
			(net 37 "/OCuLink/PCIe_{x4}.RX1+")
			(pintype "passive")
		)
		(pad "8" smd roundrect
			(at 0.385 0 180)
			(size 0.4 0.55)
			(layers "B.Cu" "B.Mask" "B.Paste")
			(roundrect_rratio 0.25)
			(net 28 "GND")
			(pintype "passive")
		)
		(pad "9" smd roundrect
			(at 0.385 0.5 180)
			(size 0.25 0.55)
			(layers "B.Cu" "B.Mask" "B.Paste")
			(roundrect_rratio 0.25)
			(net 36 "/OCuLink/PCIe_{x4}.RX0-")
			(pintype "passive")
		)
		(pad "10" smd roundrect
			(at 0.385 1 180)
			(size 0.25 0.55)
			(layers "B.Cu" "B.Mask" "B.Paste")
			(roundrect_rratio 0.25)
			(net 39 "/OCuLink/PCIe_{x4}.RX0+")
			(pintype "passive")
		)
	)
	(footprint "antmicro-footprints:C_0402_1005Metric"
		(layer "B.Cu")
		(at 60.67 111.55)
		(descr "Capacitor SMD 0402")
		(tags "capacitor SMD 0402")
		(property "Reference" "C36"
			(at -1.07 0.55 0)
			(layer "B.SilkS")
			(effects
				(font
					(size 0.7 0.7)
					(thickness 0.15)
				)
				(justify right top mirror)
			)
		)
		(property "Value" "C_100n_0402"
			(at -1.022927 -2.155213 0)
			(layer "B.Fab")
			(hide yes)
			(effects
				(font
					(size 0.7 0.7)
					(thickness 0.15)
				)
				(justify right top mirror)
			)
		)
		(property "Datasheet" "https://www.murata.com/products/productdetail?partno=GRM155R61H104KE14%23"
			(at 0 0 0)
			(layer "B.Fab")
			(hide yes)
			(effects
				(font
					(size 1.27 1.27)
					(thickness 0.15)
				)
				(justify mirror)
			)
		)
		(property "Description" "SMD Multilayer Ceramic Capacitor, 0.1 µF, 50 V, 0402 [1005 Metric], ± 10%, X5R, GRM Series"
			(at 0 0 0)
			(layer "B.Fab")
			(hide yes)
			(effects
				(font
					(size 1.27 1.27)
					(thickness 0.15)
				)
				(justify mirror)
			)
		)
		(property "MPN" "GRM155R61H104KE14D"
			(at 0 0 0)
			(unlocked yes)
			(layer "B.Fab")
			(hide yes)
			(effects
				(font
					(size 1 1)
					(thickness 0.15)
				)
				(justify mirror)
			)
		)
		(property "Manufacturer" "Murata"
			(at 0 0 0)
			(unlocked yes)
			(layer "B.Fab")
			(hide yes)
			(effects
				(font
					(size 1 1)
					(thickness 0.15)
				)
				(justify mirror)
			)
		)
		(property "License" "Apache-2.0"
			(at 0 0 0)
			(unlocked yes)
			(layer "B.Fab")
			(hide yes)
			(effects
				(font
					(size 1 1)
					(thickness 0.15)
				)
				(justify mirror)
			)
		)
		(property "Author" "Antmicro"
			(at 0 0 0)
			(unlocked yes)
			(layer "B.Fab")
			(hide yes)
			(effects
				(font
					(size 1 1)
					(thickness 0.15)
				)
				(justify mirror)
			)
		)
		(property "Val" "100n"
			(at 0 0 0)
			(unlocked yes)
			(layer "B.Fab")
			(hide yes)
			(effects
				(font
					(size 1 1)
					(thickness 0.15)
				)
				(justify mirror)
			)
		)
		(property "Voltage" "50V"
			(at 0 0 0)
			(unlocked yes)
			(layer "B.Fab")
			(hide yes)
			(effects
				(font
					(size 1 1)
					(thickness 0.15)
				)
				(justify mirror)
			)
		)
		(property "Dielectric" "X5R"
			(at 0 0 0)
			(unlocked yes)
			(layer "B.Fab")
			(hide yes)
			(effects
				(font
					(size 1 1)
					(thickness 0.15)
				)
				(justify mirror)
			)
		)
		(sheetname "/Power/")
		(sheetfile "power.kicad_sch")
		(attr smd)
		(fp_rect
			(start -0.925 0.47)
			(end 0.925 -0.47)
			(stroke
				(width 0.05)
				(type default)
			)
			(fill no)
			(layer "B.CrtYd")
		)
		(fp_line
			(start -0.494 -0.248)
			(end -0.494 0.25)
			(stroke
				(width 0.15)
				(type solid)
			)
			(layer "B.Fab")
		)
		(fp_line
			(start -0.494 0.25)
			(end 0.504 0.25)
			(stroke
				(width 0.15)
				(type solid)
			)
			(layer "B.Fab")
		)
		(fp_line
			(start 0.504 -0.248)
			(end -0.494 -0.248)
			(stroke
				(width 0.15)
				(type solid)
			)
			(layer "B.Fab")
		)
		(fp_line
			(start 0.504 0.25)
			(end 0.504 -0.248)
			(stroke
				(width 0.15)
				(type solid)
			)
			(layer "B.Fab")
		)
		(pad "1" smd roundrect
			(at -0.48 0)
			(size 0.59 0.64)
			(layers "B.Cu" "B.Mask" "B.Paste")
			(roundrect_rratio 0.25)
			(net 28 "GND")
			(pintype "passive")
		)
		(pad "2" smd roundrect
			(at 0.48 0)
			(size 0.59 0.64)
			(layers "B.Cu" "B.Mask" "B.Paste")
			(roundrect_rratio 0.25)
			(net 312 "/Power/+1V0_OUT")
			(pintype "passive")
		)
	)
	(footprint "antmicro-footprints:TP_SMD_0.75mm"
		(layer "B.Cu")
		(at 74.224997 85.184997 180)
		(property "Reference" "TP37"
			(at 0 0.6 0)
			(layer "B.SilkS")
			(hide yes)
			(effects
				(font
					(size 0.7 0.7)
					(thickness 0.15)
				)
				(justify left bottom mirror)
			)
		)
		(property "Value" "TP_0.75mm_SMD"
			(at 0 -1.2 0)
			(layer "B.Fab")
			(hide yes)
			(effects
				(font
					(size 0.7 0.7)
					(thickness 0.15)
				)
				(justify left bottom mirror)
			)
		)
		(property "Description" "SMT test point"
			(at 0 0 0)
			(layer "B.Fab")
			(hide yes)
			(effects
				(font
					(size 1.27 1.27)
					(thickness 0.15)
				)
				(justify mirror)
			)
		)
		(property "MPN" ""
			(at 0 0 0)
			(unlocked yes)
			(layer "B.Fab")
			(hide yes)
			(effects
				(font
					(size 1 1)
					(thickness 0.15)
				)
				(justify mirror)
			)
		)
		(property "Manufacturer" ""
			(at 0 0 0)
			(unlocked yes)
			(layer "B.Fab")
			(hide yes)
			(effects
				(font
					(size 1 1)
					(thickness 0.15)
				)
				(justify mirror)
			)
		)
		(property "Author" "Antmicro"
			(at 0 0 0)
			(unlocked yes)
			(layer "B.Fab")
			(hide yes)
			(effects
				(font
					(size 1 1)
					(thickness 0.15)
				)
				(justify mirror)
			)
		)
		(property "License" "Apache-2.0"
			(at 0 0 0)
			(unlocked yes)
			(layer "B.Fab")
			(hide yes)
			(effects
				(font
					(size 1 1)
					(thickness 0.15)
				)
				(justify mirror)
			)
		)
		(sheetname "/Power/")
		(sheetfile "power.kicad_sch")
		(attr exclude_from_pos_files exclude_from_bom)
		(fp_circle
			(center 0 0)
			(end 0.475 0)
			(stroke
				(width 0.05)
				(type default)
			)
			(fill no)
			(layer "B.CrtYd")
		)
		(pad "1" smd circle
			(at 0 0 180)
			(size 0.75 0.75)
			(layers "B.Cu" "B.Mask")
			(net 255 "/Power/+3V3_OUT")
			(pinfunction "1")
			(pintype "passive")
		)
	)
	(footprint "antmicro-footprints:SOIC-8_5.3x5.3x2mm_P1.27mm"
		(layer "B.Cu")
		(at 70.15 89.852146 90)
		(descr "8-Pin SOIC 208-mil")
		(property "Reference" "U13"
			(at -1.047854 -3.75 90)
			(layer "B.SilkS")
			(effects
				(font
					(size 0.7 0.7)
					(thickness 0.15)
				)
				(justify right top mirror)
			)
		)
		(property "Value" "AT25DF641A-SH"
			(at 0 -3.8 90)
			(layer "B.Fab")
			(hide yes)
			(effects
				(font
					(size 0.7 0.7)
					(thickness 0.15)
				)
				(justify right top mirror)
			)
		)
		(property "Datasheet" "https://eu.mouser.com/datasheet/3/1166/1/REN_DS-AT25DF641A-8693G-022022_unsecure_DST_20220220_1.pdf"
			(at 0 0 90)
			(layer "B.Fab")
			(hide yes)
			(effects
				(font
					(size 1.27 1.27)
					(thickness 0.15)
				)
				(justify mirror)
			)
		)
		(property "Description" "NOR Flash 64 Mbit, 3.0V (2.7V to 3.6V), -40C to 85C, SOIC-W 208mil (Tape & Reel), Single, Dual SPI NOR flash"
			(at 0 0 90)
			(layer "B.Fab")
			(hide yes)
			(effects
				(font
					(size 1.27 1.27)
					(thickness 0.15)
				)
				(justify mirror)
			)
		)
		(property "MPN" "AT25DF641A-SH-T "
			(at 0 0 90)
			(unlocked yes)
			(layer "B.Fab")
			(hide yes)
			(effects
				(font
					(size 1 1)
					(thickness 0.15)
				)
				(justify mirror)
			)
		)
		(property "Manufacturer" "Renesas"
			(at 0 0 90)
			(unlocked yes)
			(layer "B.Fab")
			(hide yes)
			(effects
				(font
					(size 1 1)
					(thickness 0.15)
				)
				(justify mirror)
			)
		)
		(property "Author" "Antmicro"
			(at 0 0 90)
			(unlocked yes)
			(layer "B.Fab")
			(hide yes)
			(effects
				(font
					(size 1 1)
					(thickness 0.15)
				)
				(justify mirror)
			)
		)
		(property "License" "Apache-2.0"
			(at 0 0 90)
			(unlocked yes)
			(layer "B.Fab")
			(hide yes)
			(effects
				(font
					(size 1 1)
					(thickness 0.15)
				)
				(justify mirror)
			)
		)
		(sheetname "/Flash memory/")
		(sheetfile "flash-memory.kicad_sch")
		(attr smd)
		(fp_line
			(start -2.8 2.641)
			(end -4.4 2.641)
			(stroke
				(width 0.15)
				(type solid)
			)
			(layer "B.SilkS")
		)
		(fp_circle
			(center -4.85 1.905)
			(end -4.8 1.855)
			(stroke
				(width 0.15)
				(type solid)
			)
			(fill yes)
			(layer "B.SilkS")
		)
		(fp_rect
			(start 4.675 3)
			(end -4.675 -3)
			(stroke
				(width 0.05)
				(type solid)
			)
			(fill no)
			(layer "B.CrtYd")
		)
		(fp_line
			(start 2.64 -2.64)
			(end -2.641 -2.64)
			(stroke
				(width 0.15)
				(type solid)
			)
			(layer "B.Fab")
		)
		(fp_line
			(start -2.641 -2.64)
			(end -2.641 2.641)
			(stroke
				(width 0.15)
				(type solid)
			)
			(layer "B.Fab")
		)
		(fp_line
			(start -2.641 1.371)
			(end -1.371 2.641)
			(stroke
				(width 0.15)
				(type solid)
			)
			(layer "B.Fab")
		)
		(fp_line
			(start 2.64 2.641)
			(end 2.64 -2.64)
			(stroke
				(width 0.15)
				(type solid)
			)
			(layer "B.Fab")
		)
		(fp_line
			(start -2.641 2.641)
			(end 2.64 2.641)
			(stroke
				(width 0.15)
				(type solid)
			)
			(layer "B.Fab")
		)
		(pad "1" smd roundrect
			(at -3.601 1.905)
			(size 0.65 1.65)
			(layers "B.Cu" "B.Mask" "B.Paste")
			(roundrect_rratio 0.25)
			(net 105 "/Flash memory/FLASH.~{CE}")
			(pinfunction "~{CS}")
			(pintype "input")
		)
		(pad "2" smd roundrect
			(at -3.601 0.635)
			(size 0.65 1.65)
			(layers "B.Cu" "B.Mask" "B.Paste")
			(roundrect_rratio 0.25)
			(net 140 "/Flash memory/FLASH.MISO")
			(pinfunction "SO")
			(pintype "bidirectional")
		)
		(pad "3" smd roundrect
			(at -3.601 -0.633)
			(size 0.65 1.65)
			(layers "B.Cu" "B.Mask" "B.Paste")
			(roundrect_rratio 0.25)
			(net 72 "/Flash memory/~{WP}")
			(pinfunction "~{WP}")
			(pintype "bidirectional")
		)
		(pad "4" smd roundrect
			(at -3.601 -1.904)
			(size 0.65 1.65)
			(layers "B.Cu" "B.Mask" "B.Paste")
			(roundrect_rratio 0.25)
			(net 28 "GND")
			(pinfunction "GND")
			(pintype "power_in")
		)
		(pad "5" smd roundrect
			(at 3.6 -1.904)
			(size 0.65 1.65)
			(layers "B.Cu" "B.Mask" "B.Paste")
			(roundrect_rratio 0.25)
			(net 139 "/Flash memory/FLASH.MOSI")
			(pinfunction "SI")
			(pintype "bidirectional")
		)
		(pad "6" smd roundrect
			(at 3.6 -0.633)
			(size 0.65 1.65)
			(layers "B.Cu" "B.Mask" "B.Paste")
			(roundrect_rratio 0.25)
			(net 106 "/Flash memory/FLASH.CLK")
			(pinfunction "SCK")
			(pintype "input")
		)
		(pad "7" smd roundrect
			(at 3.6 0.635)
			(size 0.65 1.65)
			(layers "B.Cu" "B.Mask" "B.Paste")
			(roundrect_rratio 0.25)
			(net 71 "/Flash memory/~{HOLD}")
			(pinfunction "~{HOLD}")
			(pintype "bidirectional")
		)
		(pad "8" smd roundrect
			(at 3.6 1.905)
			(size 0.65 1.65)
			(layers "B.Cu" "B.Mask" "B.Paste")
			(roundrect_rratio 0.25)
			(net 110 "/Flash memory/+3V3_FLASH")
			(pinfunction "VCC")
			(pintype "power_in")
		)
	)
)
